(kicad_pcb
	(version 20260206)
	(generator "pcbnew")
	(generator_version "10.0")
	(general
		(thickness 1.6)
		(legacy_teardrops no)
	)
	(paper "A4")
	(title_block
		(title "9052_F0T_PDB_Converter_Brick_F_V03_1208_1600_OCP.brd")
		(comment 1 "Grand Teton / footprints 207-216 of 578")
	)
	(layers
		(0 "F.Cu" signal "TOP")
		(4 "In1.Cu" signal "GND")
		(6 "In2.Cu" signal "IN1")
		(8 "In3.Cu" signal "GND1")
		(10 "In4.Cu" signal "VCC")
		(12 "In5.Cu" signal "VCC1")
		(14 "In6.Cu" signal "GND2")
		(16 "In7.Cu" signal "IN2")
		(18 "In8.Cu" signal "GND3")
		(2 "B.Cu" signal "BOTTOM")
		(9 "F.Adhes" user "F.Adhesive")
		(11 "B.Adhes" user "B.Adhesive")
		(13 "F.Paste" user "Package Geometry/Pastemask Top")
		(15 "B.Paste" user "Package Geometry/Pastemask Bottom")
		(5 "F.SilkS" user "Ref Des/Silkscreen Top")
		(7 "B.SilkS" user "Ref Des/Silkscreen Bottom")
		(1 "F.Mask" user "Board Geometry/Soldermask Top")
		(3 "B.Mask" user "Board Geometry/Soldermask Bottom")
		(17 "Dwgs.User" user "User.Drawings")
		(19 "Cmts.User" user "User.Comments")
		(21 "Eco1.User" user "User.Eco1")
		(23 "Eco2.User" user "User.Eco2")
		(25 "Edge.Cuts" user "Board Geometry/Outline")
		(27 "Margin" user)
		(31 "F.CrtYd" user "Package Geometry/Place Bound Top")
		(29 "B.CrtYd" user "Package Geometry/Place Bound Bottom")
		(35 "F.Fab" user "Ref Des/Assembly Top")
		(33 "B.Fab" user "Ref Des/Assembly Bottom")
	)
	(footprint ""
		(layer "F.Cu")
		(at 48.768 -17.78)
		(property "Reference" "ME3"
			(at 0 0 0)
			(layer "F.SilkS")
			(hide yes)
			(effects
				(font
					(size 1.27 1.27)
				)
			)
		)
		(property "Value" ""
			(at 0 0 0)
			(layer "F.Fab")
			(effects
				(font
					(size 1.27 1.27)
				)
			)
		)
		(duplicate_pad_numbers_are_jumpers no)
	)
	(footprint ""
		(layer "F.Cu")
		(at 299.631354 -78.217268 180)
		(property "Reference" "PR315"
			(at 2.959354 -4.393438 0)
			(unlocked yes)
			(layer "F.SilkS")
			(effects
				(font
					(size 0.7874 0.5842)
					(thickness 0.1524)
				)
				(justify left)
			)
		)
		(property "Value" ""
			(at 0 0 180)
			(layer "F.Fab")
			(effects
				(font
					(size 1.27 1.27)
				)
			)
		)
		(duplicate_pad_numbers_are_jumpers no)
		(fp_line
			(start 3.9878 3.5814)
			(end -3.9878 3.5814)
			(stroke
				(width 0.1524)
				(type default)
			)
			(layer "F.SilkS")
		)
		(fp_line
			(start 3.9878 -3.5814)
			(end 3.9878 3.5814)
			(stroke
				(width 0.1524)
				(type default)
			)
			(layer "F.SilkS")
		)
		(fp_line
			(start -3.9878 3.5814)
			(end -3.9878 -3.5814)
			(stroke
				(width 0.1524)
				(type default)
			)
			(layer "F.SilkS")
		)
		(fp_line
			(start -3.9878 -3.5814)
			(end 3.9878 -3.5814)
			(stroke
				(width 0.1524)
				(type default)
			)
			(layer "F.SilkS")
		)
		(fp_line
			(start 3.5306 3.353054)
			(end -3.5306 3.353054)
			(stroke
				(width 0.1)
				(type default)
			)
			(layer "F.Fab")
		)
		(fp_line
			(start 3.5306 -3.353054)
			(end 3.5306 3.353054)
			(stroke
				(width 0.1)
				(type default)
			)
			(layer "F.Fab")
		)
		(fp_line
			(start -3.5306 3.353054)
			(end -3.5306 -3.353054)
			(stroke
				(width 0.1)
				(type default)
			)
			(layer "F.Fab")
		)
		(fp_line
			(start -3.5306 -3.353054)
			(end 3.5306 -3.353054)
			(stroke
				(width 0.1)
				(type default)
			)
			(layer "F.Fab")
		)
		(pad "1A" smd rect
			(at -2.249932 0)
			(size 3.2004 6.858)
			(layers "F.Cu" "F.Mask" "F.Paste")
			(net "P52V_1")
		)
		(pad "1B" smd rect
			(at -0.776732 0 180)
			(size 0.254 0.508)
			(layers "F.Cu" "F.Mask" "F.Paste")
			(net "P52V_HS1_SENSE_P_R2")
		)
		(pad "2A" smd rect
			(at 2.249932 0)
			(size 3.2004 6.858)
			(layers "F.Cu" "F.Mask" "F.Paste")
			(net "P52V_HS1_DRAIN_2")
		)
		(pad "2B" smd rect
			(at 0.776732 0 180)
			(size 0.254 0.508)
			(layers "F.Cu" "F.Mask" "F.Paste")
			(net "P52V_HS1_SENSE_N_R2")
		)
	)
	(footprint ""
		(layer "F.Cu")
		(at 95.504 -51.943)
		(property "Reference" "PC86"
			(at 0 0 0)
			(layer "F.SilkS")
			(hide yes)
			(effects
				(font
					(size 1.27 1.27)
				)
			)
		)
		(property "Value" ""
			(at 0 0 0)
			(layer "F.Fab")
			(effects
				(font
					(size 1.27 1.27)
				)
			)
		)
		(duplicate_pad_numbers_are_jumpers no)
		(fp_line
			(start -1.524 -0.762)
			(end 1.524 -0.762)
			(stroke
				(width 0.1524)
				(type default)
			)
			(layer "F.SilkS")
		)
		(fp_line
			(start -1.524 0.762)
			(end -1.524 -0.762)
			(stroke
				(width 0.1524)
				(type default)
			)
			(layer "F.SilkS")
		)
		(fp_line
			(start 1.524 -0.762)
			(end 1.524 0.762)
			(stroke
				(width 0.1524)
				(type default)
			)
			(layer "F.SilkS")
		)
		(fp_line
			(start 1.524 0.762)
			(end -1.524 0.762)
			(stroke
				(width 0.1524)
				(type default)
			)
			(layer "F.SilkS")
		)
		(fp_line
			(start -1.1049 -0.724916)
			(end -1.1049 0.724916)
			(stroke
				(width 0.1)
				(type default)
			)
			(layer "F.Fab")
		)
		(fp_line
			(start -1.1049 0.724916)
			(end 1.1049 0.724916)
			(stroke
				(width 0.1)
				(type default)
			)
			(layer "F.Fab")
		)
		(fp_line
			(start 1.1049 -0.724916)
			(end -1.1049 -0.724916)
			(stroke
				(width 0.1)
				(type default)
			)
			(layer "F.Fab")
		)
		(fp_line
			(start 1.1049 0.724916)
			(end 1.1049 -0.724916)
			(stroke
				(width 0.1)
				(type default)
			)
			(layer "F.Fab")
		)
		(pad "1" smd rect
			(at -0.889 0 180)
			(size 1.016 1.27)
			(layers "F.Cu" "F.Mask" "F.Paste")
			(net "P12V_BRICK")
		)
		(pad "2" smd rect
			(at 0.889 0 180)
			(size 1.016 1.27)
			(layers "F.Cu" "F.Mask" "F.Paste")
			(net "GND")
		)
	)
	(footprint ""
		(layer "F.Cu")
		(at 277.114 -24.257 90)
		(property "Reference" "R5888"
			(at 0 0 90)
			(layer "F.SilkS")
			(hide yes)
			(effects
				(font
					(size 1.27 1.27)
				)
			)
		)
		(property "Value" ""
			(at 0 0 90)
			(layer "F.Fab")
			(effects
				(font
					(size 1.27 1.27)
				)
			)
		)
		(duplicate_pad_numbers_are_jumpers no)
		(fp_line
			(start 0.7874 -0.4064)
			(end 0.7874 0.4064)
			(stroke
				(width 0.1524)
				(type default)
			)
			(layer "F.SilkS")
		)
		(fp_line
			(start -0.7874 -0.4064)
			(end 0.7874 -0.4064)
			(stroke
				(width 0.1524)
				(type default)
			)
			(layer "F.SilkS")
		)
		(fp_line
			(start 0.7874 0.4064)
			(end -0.7874 0.4064)
			(stroke
				(width 0.1524)
				(type default)
			)
			(layer "F.SilkS")
		)
		(fp_line
			(start -0.7874 0.4064)
			(end -0.7874 -0.4064)
			(stroke
				(width 0.1524)
				(type default)
			)
			(layer "F.SilkS")
		)
		(fp_line
			(start -0.12065 -0.305054)
			(end -0.12065 -0.2794)
			(stroke
				(width 0.1)
				(type default)
			)
			(layer "F.Fab")
		)
		(fp_line
			(start -0.67945 -0.305054)
			(end -0.12065 -0.305054)
			(stroke
				(width 0.1)
				(type default)
			)
			(layer "F.Fab")
		)
		(fp_line
			(start 0.67945 -0.3048)
			(end 0.67945 0.3048)
			(stroke
				(width 0.1)
				(type default)
			)
			(layer "F.Fab")
		)
		(fp_line
			(start 0.12065 -0.3048)
			(end 0.67945 -0.3048)
			(stroke
				(width 0.1)
				(type default)
			)
			(layer "F.Fab")
		)
		(fp_line
			(start 0.12065 -0.2794)
			(end 0.12065 -0.3048)
			(stroke
				(width 0.1)
				(type default)
			)
			(layer "F.Fab")
		)
		(fp_line
			(start -0.12065 -0.2794)
			(end 0.12065 -0.2794)
			(stroke
				(width 0.1)
				(type default)
			)
			(layer "F.Fab")
		)
		(fp_line
			(start 0.120396 0.2794)
			(end -0.12065 0.2794)
			(stroke
				(width 0.1)
				(type default)
			)
			(layer "F.Fab")
		)
		(fp_line
			(start -0.12065 0.2794)
			(end -0.12065 0.3048)
			(stroke
				(width 0.1)
				(type default)
			)
			(layer "F.Fab")
		)
		(fp_line
			(start 0.67945 0.3048)
			(end 0.120396 0.3048)
			(stroke
				(width 0.1)
				(type default)
			)
			(layer "F.Fab")
		)
		(fp_line
			(start 0.120396 0.3048)
			(end 0.120396 0.2794)
			(stroke
				(width 0.1)
				(type default)
			)
			(layer "F.Fab")
		)
		(fp_line
			(start -0.12065 0.3048)
			(end -0.67945 0.3048)
			(stroke
				(width 0.1)
				(type default)
			)
			(layer "F.Fab")
		)
		(fp_line
			(start -0.67945 0.3048)
			(end -0.67945 -0.305054)
			(stroke
				(width 0.1)
				(type default)
			)
			(layer "F.Fab")
		)
		(pad "1" smd circle
			(at -0.40005 0 90)
			(size 0 0)
			(layers "F.Cu" "F.Mask" "F.Paste")
			(net "P3V3_AND")
		)
		(pad "2" smd circle
			(at 0.40005 0 90)
			(size 0 0)
			(layers "F.Cu" "F.Mask" "F.Paste")
			(net "GND")
		)
	)
	(footprint ""
		(layer "F.Cu")
		(at 162.687 -49.911)
		(property "Reference" "PC35"
			(at 0 0 0)
			(layer "F.SilkS")
			(hide yes)
			(effects
				(font
					(size 1.27 1.27)
				)
			)
		)
		(property "Value" ""
			(at 0 0 0)
			(layer "F.Fab")
			(effects
				(font
					(size 1.27 1.27)
				)
			)
		)
		(duplicate_pad_numbers_are_jumpers no)
		(fp_line
			(start -1.524 -0.762)
			(end 1.524 -0.762)
			(stroke
				(width 0.1524)
				(type default)
			)
			(layer "F.SilkS")
		)
		(fp_line
			(start -1.524 0.762)
			(end -1.524 -0.762)
			(stroke
				(width 0.1524)
				(type default)
			)
			(layer "F.SilkS")
		)
		(fp_line
			(start 1.524 -0.762)
			(end 1.524 0.762)
			(stroke
				(width 0.1524)
				(type default)
			)
			(layer "F.SilkS")
		)
		(fp_line
			(start 1.524 0.762)
			(end -1.524 0.762)
			(stroke
				(width 0.1524)
				(type default)
			)
			(layer "F.SilkS")
		)
		(fp_line
			(start -1.1049 -0.724916)
			(end -1.1049 0.724916)
			(stroke
				(width 0.1)
				(type default)
			)
			(layer "F.Fab")
		)
		(fp_line
			(start -1.1049 0.724916)
			(end 1.1049 0.724916)
			(stroke
				(width 0.1)
				(type default)
			)
			(layer "F.Fab")
		)
		(fp_line
			(start 1.1049 -0.724916)
			(end -1.1049 -0.724916)
			(stroke
				(width 0.1)
				(type default)
			)
			(layer "F.Fab")
		)
		(fp_line
			(start 1.1049 0.724916)
			(end 1.1049 -0.724916)
			(stroke
				(width 0.1)
				(type default)
			)
			(layer "F.Fab")
		)
		(pad "1" smd rect
			(at -0.889 0 180)
			(size 1.016 1.27)
			(layers "F.Cu" "F.Mask" "F.Paste")
			(net "P12V_BRICK")
		)
		(pad "2" smd rect
			(at 0.889 0 180)
			(size 1.016 1.27)
			(layers "F.Cu" "F.Mask" "F.Paste")
			(net "GND")
		)
	)
	(footprint ""
		(layer "F.Cu")
		(at 286.383222 -48.960024)
		(property "Reference" "PC560"
			(at 0 0 0)
			(layer "F.SilkS")
			(hide yes)
			(effects
				(font
					(size 1.27 1.27)
				)
			)
		)
		(property "Value" ""
			(at 0 0 0)
			(layer "F.Fab")
			(effects
				(font
					(size 1.27 1.27)
				)
			)
		)
		(duplicate_pad_numbers_are_jumpers no)
		(fp_line
			(start -0.7874 -0.4064)
			(end 0.7874 -0.4064)
			(stroke
				(width 0.1524)
				(type default)
			)
			(layer "F.SilkS")
		)
		(fp_line
			(start -0.7874 0.4064)
			(end -0.7874 -0.4064)
			(stroke
				(width 0.1524)
				(type default)
			)
			(layer "F.SilkS")
		)
		(fp_line
			(start 0.7874 -0.4064)
			(end 0.7874 0.4064)
			(stroke
				(width 0.1524)
				(type default)
			)
			(layer "F.SilkS")
		)
		(fp_line
			(start 0.7874 0.4064)
			(end -0.7874 0.4064)
			(stroke
				(width 0.1524)
				(type default)
			)
			(layer "F.SilkS")
		)
		(fp_line
			(start -0.67945 -0.305054)
			(end -0.12065 -0.305054)
			(stroke
				(width 0.1)
				(type default)
			)
			(layer "F.Fab")
		)
		(fp_line
			(start -0.67945 0.3048)
			(end -0.67945 -0.305054)
			(stroke
				(width 0.1)
				(type default)
			)
			(layer "F.Fab")
		)
		(fp_line
			(start -0.12065 -0.305054)
			(end -0.12065 -0.2794)
			(stroke
				(width 0.1)
				(type default)
			)
			(layer "F.Fab")
		)
		(fp_line
			(start -0.12065 -0.2794)
			(end 0.12065 -0.2794)
			(stroke
				(width 0.1)
				(type default)
			)
			(layer "F.Fab")
		)
		(fp_line
			(start -0.12065 0.2794)
			(end -0.12065 0.3048)
			(stroke
				(width 0.1)
				(type default)
			)
			(layer "F.Fab")
		)
		(fp_line
			(start -0.12065 0.3048)
			(end -0.67945 0.3048)
			(stroke
				(width 0.1)
				(type default)
			)
			(layer "F.Fab")
		)
		(fp_line
			(start 0.120396 0.2794)
			(end -0.12065 0.2794)
			(stroke
				(width 0.1)
				(type default)
			)
			(layer "F.Fab")
		)
		(fp_line
			(start 0.120396 0.3048)
			(end 0.120396 0.2794)
			(stroke
				(width 0.1)
				(type default)
			)
			(layer "F.Fab")
		)
		(fp_line
			(start 0.12065 -0.3048)
			(end 0.67945 -0.3048)
			(stroke
				(width 0.1)
				(type default)
			)
			(layer "F.Fab")
		)
		(fp_line
			(start 0.12065 -0.2794)
			(end 0.12065 -0.3048)
			(stroke
				(width 0.1)
				(type default)
			)
			(layer "F.Fab")
		)
		(fp_line
			(start 0.67945 -0.3048)
			(end 0.67945 0.3048)
			(stroke
				(width 0.1)
				(type default)
			)
			(layer "F.Fab")
		)
		(fp_line
			(start 0.67945 0.3048)
			(end 0.120396 0.3048)
			(stroke
				(width 0.1)
				(type default)
			)
			(layer "F.Fab")
		)
		(pad "1" smd circle
			(at -0.40005 0)
			(size 0 0)
			(layers "F.Cu" "F.Mask" "F.Paste")
			(net "P52V_HS1_TEMPP")
		)
		(pad "2" smd circle
			(at 0.40005 0)
			(size 0 0)
			(layers "F.Cu" "F.Mask" "F.Paste")
			(net "P52V_HS1_TEMPN")
		)
	)
	(footprint ""
		(layer "F.Cu")
		(at 84.713826 -127.889)
		(property "Reference" "PC50"
			(at 0 0 0)
			(layer "F.SilkS")
			(hide yes)
			(effects
				(font
					(size 1.27 1.27)
				)
			)
		)
		(property "Value" ""
			(at 0 0 0)
			(layer "F.Fab")
			(effects
				(font
					(size 1.27 1.27)
				)
			)
		)
		(duplicate_pad_numbers_are_jumpers no)
		(fp_line
			(start -2.2098 -0.9398)
			(end 2.2098 -0.9398)
			(stroke
				(width 0.1524)
				(type default)
			)
			(layer "F.SilkS")
		)
		(fp_line
			(start -2.2098 0.9398)
			(end -2.2098 -0.9398)
			(stroke
				(width 0.1524)
				(type default)
			)
			(layer "F.SilkS")
		)
		(fp_line
			(start 2.2098 -0.9398)
			(end 2.2098 0.9398)
			(stroke
				(width 0.1524)
				(type default)
			)
			(layer "F.SilkS")
		)
		(fp_line
			(start 2.2098 0.9398)
			(end -2.2098 0.9398)
			(stroke
				(width 0.1524)
				(type default)
			)
			(layer "F.SilkS")
		)
		(fp_line
			(start -1.700022 -0.899922)
			(end 1.700022 -0.899922)
			(stroke
				(width 0.1)
				(type default)
			)
			(layer "F.Fab")
		)
		(fp_line
			(start -1.700022 0.899922)
			(end -1.700022 -0.899922)
			(stroke
				(width 0.1)
				(type default)
			)
			(layer "F.Fab")
		)
		(fp_line
			(start 1.700022 -0.899922)
			(end 1.700022 0.899922)
			(stroke
				(width 0.1)
				(type default)
			)
			(layer "F.Fab")
		)
		(fp_line
			(start 1.700022 0.899922)
			(end -1.700022 0.899922)
			(stroke
				(width 0.1)
				(type default)
			)
			(layer "F.Fab")
		)
		(pad "1" smd rect
			(at -1.4732 0 180)
			(size 1.1684 1.5748)
			(layers "F.Cu" "F.Mask" "F.Paste")
			(net "P52V_HS_FILTER")
		)
		(pad "2" smd rect
			(at 1.4732 0 180)
			(size 1.1684 1.5748)
			(layers "F.Cu" "F.Mask" "F.Paste")
			(net "GND")
		)
	)
	(footprint ""
		(layer "F.Cu")
		(at 315.000132 -132.40004 -90)
		(property "Reference" "H19"
			(at -6.13029 1.056132 0)
			(unlocked yes)
			(layer "F.SilkS")
			(effects
				(font
					(size 0.7874 0.5842)
					(thickness 0.1524)
				)
				(justify left)
			)
		)
		(property "Value" ""
			(at 0 0 270)
			(layer "F.Fab")
			(effects
				(font
					(size 1.27 1.27)
				)
			)
		)
		(duplicate_pad_numbers_are_jumpers no)
		(pad "1" thru_hole circle
			(at 0 0 270)
			(size 10.16 10.16)
			(drill 6.4008
				(offset 0 0)
			)
			(layers "*.Cu" "*.Mask")
			(remove_unused_layers no)
			(net "GND")
			(clearance -1.6256)
			(padstack
				(mode front_inner_back)
				(layer "Inner"
					(shape circle)
					(size 10.16 10.16)
					(clearance -1.6256)
				)
				(layer "B.Cu"
					(shape oval)
					(size 10.0076 32.004)
					(offset 0 10.9982)
					(clearance -1.5494)
				)
			)
		)
	)
	(footprint ""
		(layer "F.Cu")
		(at 209.291174 -60.96)
		(property "Reference" "PC134"
			(at -1.773174 -3.65633 0)
			(unlocked yes)
			(layer "F.SilkS")
			(effects
				(font
					(size 0.7874 0.5842)
					(thickness 0.1524)
				)
				(justify left)
			)
		)
		(property "Value" ""
			(at 0 0 0)
			(layer "F.Fab")
			(effects
				(font
					(size 1.27 1.27)
				)
			)
		)
		(duplicate_pad_numbers_are_jumpers no)
		(fp_line
			(start 5.2578 2.499868)
			(end -5.2578 2.499868)
			(stroke
				(width 0.1524)
				(type default)
			)
			(layer "F.SilkS")
		)
		(fp_circle
			(center 0 2.499868)
			(end 5.2578 2.499868)
			(stroke
				(width 0.1524)
				(type default)
			)
			(fill no)
			(layer "F.SilkS")
		)
		(fp_poly
			(pts
				(arc
					(start 5.2578 2.499868)
					(mid 0 7.757922)
					(end -5.2578 2.499868)
				)
			)
			(stroke
				(width 0)
				(type default)
			)
			(fill yes)
			(layer "F.SilkS")
		)
		(fp_circle
			(center 0 2.499868)
			(end 5.2578 2.499868)
			(stroke
				(width 0.1)
				(type default)
			)
			(fill no)
			(layer "F.Fab")
		)
		(pad "1" thru_hole rect
			(at 0 0 270)
			(size 1.524 1.524)
			(drill 1.016)
			(layers "*.Cu" "*.Mask")
			(remove_unused_layers no)
			(net "P12V_BRICK")
			(clearance 0)
			(padstack
				(mode front_inner_back)
				(layer "Inner"
					(shape circle)
					(size 1.524 1.524)
					(clearance 0)
				)
				(layer "B.Cu"
					(shape rect)
					(size 1.524 1.524)
					(clearance 0)
				)
			)
		)
		(pad "2" thru_hole circle
			(at 0 4.99999 270)
			(size 1.524 1.524)
			(drill 1.016)
			(layers "*.Cu" "*.Mask")
			(remove_unused_layers no)
			(net "GND")
			(clearance 0)
		)
	)
	(footprint ""
		(layer "F.Cu")
		(at 100.076 -62.738)
		(property "Reference" "PC56"
			(at 0 0 0)
			(layer "F.SilkS")
			(hide yes)
			(effects
				(font
					(size 1.27 1.27)
				)
			)
		)
		(property "Value" ""
			(at 0 0 0)
			(layer "F.Fab")
			(effects
				(font
					(size 1.27 1.27)
				)
			)
		)
		(duplicate_pad_numbers_are_jumpers no)
		(fp_line
			(start -0.7874 -0.4064)
			(end 0.7874 -0.4064)
			(stroke
				(width 0.1524)
				(type default)
			)
			(layer "F.SilkS")
		)
		(fp_line
			(start -0.7874 0.4064)
			(end -0.7874 -0.4064)
			(stroke
				(width 0.1524)
				(type default)
			)
			(layer "F.SilkS")
		)
		(fp_line
			(start 0.7874 -0.4064)
			(end 0.7874 0.4064)
			(stroke
				(width 0.1524)
				(type default)
			)
			(layer "F.SilkS")
		)
		(fp_line
			(start 0.7874 0.4064)
			(end -0.7874 0.4064)
			(stroke
				(width 0.1524)
				(type default)
			)
			(layer "F.SilkS")
		)
		(fp_line
			(start -0.6858 -0.3048)
			(end -0.1016 -0.3048)
			(stroke
				(width 0.1)
				(type default)
			)
			(layer "F.Fab")
		)
		(fp_line
			(start -0.6858 0.3048)
			(end -0.6858 -0.3048)
			(stroke
				(width 0.1)
				(type default)
			)
			(layer "F.Fab")
		)
		(fp_line
			(start -0.1016 -0.3048)
			(end -0.1016 -0.2794)
			(stroke
				(width 0.1)
				(type default)
			)
			(layer "F.Fab")
		)
		(fp_line
			(start -0.1016 -0.2794)
			(end 0.1016 -0.2794)
			(stroke
				(width 0.1)
				(type default)
			)
			(layer "F.Fab")
		)
		(fp_line
			(start -0.1016 0.2794)
			(end -0.1016 0.3048)
			(stroke
				(width 0.1)
				(type default)
			)
			(layer "F.Fab")
		)
		(fp_line
			(start -0.1016 0.3048)
			(end -0.6858 0.3048)
			(stroke
				(width 0.1)
				(type default)
			)
			(layer "F.Fab")
		)
		(fp_line
			(start 0.1016 -0.3048)
			(end 0.6858 -0.3048)
			(stroke
				(width 0.1)
				(type default)
			)
			(layer "F.Fab")
		)
		(fp_line
			(start 0.1016 -0.2794)
			(end 0.1016 -0.3048)
			(stroke
				(width 0.1)
				(type default)
			)
			(layer "F.Fab")
		)
		(fp_line
			(start 0.1016 0.2794)
			(end -0.1016 0.2794)
			(stroke
				(width 0.1)
				(type default)
			)
			(layer "F.Fab")
		)
		(fp_line
			(start 0.1016 0.3048)
			(end 0.1016 0.2794)
			(stroke
				(width 0.1)
				(type default)
			)
			(layer "F.Fab")
		)
		(fp_line
			(start 0.6858 -0.3048)
			(end 0.6858 0.3048)
			(stroke
				(width 0.1)
				(type default)
			)
			(layer "F.Fab")
		)
		(fp_line
			(start 0.6858 0.3048)
			(end 0.1016 0.3048)
			(stroke
				(width 0.1)
				(type default)
			)
			(layer "F.Fab")
		)
		(pad "1" smd rect
			(at -0.40005 0 180)
			(size 0.4572 0.508)
			(layers "F.Cu" "F.Mask" "F.Paste")
			(net "P12V_BRICK")
		)
		(pad "2" smd rect
			(at 0.40005 0 180)
			(size 0.4572 0.508)
			(layers "F.Cu" "F.Mask" "F.Paste")
			(net "GND")
		)
	)
)
